# BASEBOARD_FAB2 (Tioga Pass) — schematic netlist excerpt (pin names and nets, part order shuffled) for the footprints in the layout excerpt that follows; sources: Cadence DE-HDL packaged netlist, KiCad conversion of Wiwynn_Tioga_Pass_MB.brd

U25W16  TTL3126  74CBTLV3126 IC  pkg QFNLF  page 255
  OE(3)  = BMC_JTAG_SEL_BUF
  A(3)  = JTAG_BMC_TDI
  B(3)  = JTAG_BMC_BUF_TDI
  OE(2)  = BMC_JTAG_SEL_BUF
  A(2)  = JTAG_BMC_TMS
  B(2)  = JTAG_BMC_BUF_TMS
  B(1)  = JTAG_BMC_BUF_TDO
  A(1)  = JTAG_BMC_TDO
  OE(1)  = BMC_JTAG_SEL_BUF
  B(0)  = BMC_PWR_DEBUG_BUF_N
  A(0)  = BMC_PWR_DEBUG_N
  OE(0)  = BMC_JTAG_SEL_BUF

(kicad_pcb
	(version 20260206)
	(generator "pcbnew")
	(generator_version "10.0")
	(general
		(thickness 1.6)
		(legacy_teardrops no)
	)
	(paper "A4")
	(title_block
		(title "Wiwynn_Tioga_Pass_MB.brd")
		(comment 1 "Tioga Pass / footprints 3055-3055 of 4770")
	)
	(layers
		(0 "F.Cu" signal "TOP")
		(4 "In1.Cu" signal "L2GND")
		(6 "In2.Cu" signal "L3")
		(8 "In3.Cu" signal "L4GND")
		(10 "In4.Cu" signal "L5")
		(12 "In5.Cu" signal "L6GND")
		(14 "In6.Cu" signal "L7VCC")
		(16 "In7.Cu" signal "L8VCC")
		(18 "In8.Cu" signal "L9GND")
		(20 "In9.Cu" signal "L10")
		(22 "In10.Cu" signal "L11GND")
		(24 "In11.Cu" signal "L12")
		(26 "In12.Cu" signal "L13GND")
		(2 "B.Cu" signal "BOTTOM")
		(9 "F.Adhes" user "F.Adhesive")
		(11 "B.Adhes" user "B.Adhesive")
		(13 "F.Paste" user "Package Geometry/Pastemask Top")
		(15 "B.Paste" user "Package Geometry/Pastemask Bottom")
		(5 "F.SilkS" user "Ref Des/Silkscreen Top")
		(7 "B.SilkS" user "Ref Des/Silkscreen Bottom")
		(1 "F.Mask" user "Board Geometry/Soldermask Top")
		(3 "B.Mask" user "Board Geometry/Soldermask Bottom")
		(17 "Dwgs.User" user "User.Drawings")
		(19 "Cmts.User" user "User.Comments")
		(21 "Eco1.User" user "User.Eco1")
		(23 "Eco2.User" user "User.Eco2")
		(25 "Edge.Cuts" user "Board Geometry/Outline")
		(27 "Margin" user)
		(31 "F.CrtYd" user "Package Geometry/Place Bound Top")
		(29 "B.CrtYd" user "Package Geometry/Place Bound Bottom")
		(35 "F.Fab" user "Ref Des/Assembly Top")
		(33 "B.Fab" user "Ref Des/Assembly Bottom")
	)
	(footprint ""
		(layer "B.Cu")
		(at 446.129918 -143.21536 90)
		(property "Reference" "U25W16"
			(at 1.743964 -3.834638 90)
			(unlocked yes)
			(layer "B.SilkS")
			(effects
				(font
					(size 3.048 1.524)
					(thickness 0.000001)
				)
				(justify left mirror)
			)
		)
		(property "Value" ""
			(at 0 0 90)
			(layer "B.Fab")
			(effects
				(font
					(size 1.27 1.27)
				)
				(justify mirror)
			)
		)
		(duplicate_pad_numbers_are_jumpers no)
		(fp_circle
			(center 1.17856 -2.466086)
			(end 1.17856 -2.339086)
			(stroke
				(width 0.254)
				(type default)
			)
			(fill no)
			(layer "B.SilkS")
		)
		(fp_rect
			(start 0.9144 0.9144)
			(end -0.9144 -0.9144)
			(stroke
				(width 0)
				(type default)
			)
			(fill yes)
			(layer "B.Paste")
		)
		(fp_rect
			(start 1.82499 1.82499)
			(end -1.82499 -1.82499)
			(stroke
				(width 0)
				(type default)
			)
			(fill no)
			(layer "B.CrtYd")
		)
		(fp_line
			(start 1.82499 -1.82499)
			(end -1.82499 -1.82499)
			(stroke
				(width 0.1)
				(type default)
			)
			(layer "B.Fab")
		)
		(fp_line
			(start -1.82499 -1.82499)
			(end -1.82499 1.82499)
			(stroke
				(width 0.1)
				(type default)
			)
			(layer "B.Fab")
		)
		(fp_line
			(start 1.82499 1.82499)
			(end 1.82499 -1.82499)
			(stroke
				(width 0.1)
				(type default)
			)
			(layer "B.Fab")
		)
		(fp_line
			(start -1.82499 1.82499)
			(end 1.82499 1.82499)
			(stroke
				(width 0.1)
				(type default)
			)
			(layer "B.Fab")
		)
		(fp_circle
			(center 1.17856 -2.466086)
			(end 1.17856 -2.339086)
			(stroke
				(width 0.254)
				(type default)
			)
			(fill no)
			(layer "B.Fab")
		)
		(pad "1" smd custom
			(at 0.750062 -1.549908 270)
			(size 0.0762 0.0762)
			(layers "B.Cu" "B.Mask" "B.Paste")
			(net "BMC_JTAG_SEL_BUF")
			(options
				(clearance outline)
				(anchor circle)
			)
			(primitives
				(gr_poly
					(pts
						(xy 0.1524 0.381)
						(arc
							(start 0.1524 -0.2286)
							(mid 0 -0.381)
							(end -0.1524 -0.2286)
						)
						(xy -0.1524 0.381)
					)
					(width 0)
					(fill yes)
				)
			)
		)
		(pad "2" smd custom
			(at 1.549908 -0.999998 270)
			(size 0.0762 0.0762)
			(layers "B.Cu" "B.Mask" "B.Paste")
			(net "JTAG_BMC_TDI")
			(options
				(clearance outline)
				(anchor circle)
			)
			(primitives
				(gr_poly
					(pts
						(xy -0.381 0.1524)
						(arc
							(start 0.2286 0.1524)
							(mid 0.381 0)
							(end 0.2286 -0.1524)
						)
						(xy -0.381 -0.1524)
					)
					(width 0)
					(fill yes)
				)
			)
		)
		(pad "3" smd custom
			(at 1.549908 -0.500126 270)
			(size 0.0762 0.0762)
			(layers "B.Cu" "B.Mask" "B.Paste")
			(net "JTAG_BMC_BUF_TDI")
			(options
				(clearance outline)
				(anchor circle)
			)
			(primitives
				(gr_poly
					(pts
						(xy -0.381 0.1524)
						(arc
							(start 0.2286 0.1524)
							(mid 0.381 0)
							(end 0.2286 -0.1524)
						)
						(xy -0.381 -0.1524)
					)
					(width 0)
					(fill yes)
				)
			)
		)
		(pad "4" smd custom
			(at 1.549908 0 270)
			(size 0.0762 0.0762)
			(layers "B.Cu" "B.Mask" "B.Paste")
			(net "BMC_JTAG_SEL_BUF")
			(options
				(clearance outline)
				(anchor circle)
			)
			(primitives
				(gr_poly
					(pts
						(xy -0.381 0.1524)
						(arc
							(start 0.2286 0.1524)
							(mid 0.381 0)
							(end 0.2286 -0.1524)
						)
						(xy -0.381 -0.1524)
					)
					(width 0)
					(fill yes)
				)
			)
		)
		(pad "5" smd custom
			(at 1.549908 0.500126 270)
			(size 0.0762 0.0762)
			(layers "B.Cu" "B.Mask" "B.Paste")
			(net "JTAG_BMC_TMS")
			(options
				(clearance outline)
				(anchor circle)
			)
			(primitives
				(gr_poly
					(pts
						(xy -0.381 0.1524)
						(arc
							(start 0.2286 0.1524)
							(mid 0.381 0)
							(end 0.2286 -0.1524)
						)
						(xy -0.381 -0.1524)
					)
					(width 0)
					(fill yes)
				)
			)
		)
		(pad "6" smd custom
			(at 1.549908 0.999998 270)
			(size 0.0762 0.0762)
			(layers "B.Cu" "B.Mask" "B.Paste")
			(net "JTAG_BMC_BUF_TMS")
			(options
				(clearance outline)
				(anchor circle)
			)
			(primitives
				(gr_poly
					(pts
						(xy -0.381 0.1524)
						(arc
							(start 0.2286 0.1524)
							(mid 0.381 0)
							(end 0.2286 -0.1524)
						)
						(xy -0.381 -0.1524)
					)
					(width 0)
					(fill yes)
				)
			)
		)
		(pad "7" smd custom
			(at 0.750062 1.549908 270)
			(size 0.0762 0.0762)
			(layers "B.Cu" "B.Mask" "B.Paste")
			(net "GND")
			(options
				(clearance outline)
				(anchor circle)
			)
			(primitives
				(gr_poly
					(pts
						(xy -0.1524 -0.381)
						(arc
							(start -0.1524 0.2286)
							(mid 0 0.381)
							(end 0.1524 0.2286)
						)
						(xy 0.1524 -0.381)
					)
					(width 0)
					(fill yes)
				)
			)
		)
		(pad "8" smd custom
			(at -0.769874 1.549908 270)
			(size 0.0762 0.0762)
			(layers "B.Cu" "B.Mask" "B.Paste")
			(net "JTAG_BMC_BUF_TDO")
			(options
				(clearance outline)
				(anchor circle)
			)
			(primitives
				(gr_poly
					(pts
						(xy -0.1524 -0.381)
						(arc
							(start -0.1524 0.2286)
							(mid 0 0.381)
							(end 0.1524 0.2286)
						)
						(xy 0.1524 -0.381)
					)
					(width 0)
					(fill yes)
				)
			)
		)
		(pad "9" smd custom
			(at -1.549908 0.999998 270)
			(size 0.0762 0.0762)
			(layers "B.Cu" "B.Mask" "B.Paste")
			(net "JTAG_BMC_TDO")
			(options
				(clearance outline)
				(anchor circle)
			)
			(primitives
				(gr_poly
					(pts
						(xy 0.381 -0.1524)
						(arc
							(start -0.2286 -0.1524)
							(mid -0.381 0)
							(end -0.2286 0.1524)
						)
						(xy 0.381 0.1524)
					)
					(width 0)
					(fill yes)
				)
			)
		)
		(pad "10" smd custom
			(at -1.549908 0.500126 270)
			(size 0.0762 0.0762)
			(layers "B.Cu" "B.Mask" "B.Paste")
			(net "BMC_JTAG_SEL_BUF")
			(options
				(clearance outline)
				(anchor circle)
			)
			(primitives
				(gr_poly
					(pts
						(xy 0.381 -0.1524)
						(arc
							(start -0.2286 -0.1524)
							(mid -0.381 0)
							(end -0.2286 0.1524)
						)
						(xy 0.381 0.1524)
					)
					(width 0)
					(fill yes)
				)
			)
		)
		(pad "11" smd custom
			(at -1.549908 0 270)
			(size 0.0762 0.0762)
			(layers "B.Cu" "B.Mask" "B.Paste")
			(net "BMC_PWR_DEBUG_BUF_N")
			(options
				(clearance outline)
				(anchor circle)
			)
			(primitives
				(gr_poly
					(pts
						(xy 0.381 -0.1524)
						(arc
							(start -0.2286 -0.1524)
							(mid -0.381 0)
							(end -0.2286 0.1524)
						)
						(xy 0.381 0.1524)
					)
					(width 0)
					(fill yes)
				)
			)
		)
		(pad "12" smd custom
			(at -1.549908 -0.500126 270)
			(size 0.0762 0.0762)
			(layers "B.Cu" "B.Mask" "B.Paste")
			(net "BMC_PWR_DEBUG_N")
			(options
				(clearance outline)
				(anchor circle)
			)
			(primitives
				(gr_poly
					(pts
						(xy 0.381 -0.1524)
						(arc
							(start -0.2286 -0.1524)
							(mid -0.381 0)
							(end -0.2286 0.1524)
						)
						(xy 0.381 0.1524)
					)
					(width 0)
					(fill yes)
				)
			)
		)
		(pad "13" smd custom
			(at -1.549908 -0.999998 270)
			(size 0.0762 0.0762)
			(layers "B.Cu" "B.Mask" "B.Paste")
			(net "BMC_JTAG_SEL_BUF")
			(options
				(clearance outline)
				(anchor circle)
			)
			(primitives
				(gr_poly
					(pts
						(xy 0.381 -0.1524)
						(arc
							(start -0.2286 -0.1524)
							(mid -0.381 0)
							(end -0.2286 0.1524)
						)
						(xy 0.381 0.1524)
					)
					(width 0)
					(fill yes)
				)
			)
		)
		(pad "14" smd custom
			(at -0.750062 -1.549908 270)
			(size 0.0762 0.0762)
			(layers "B.Cu" "B.Mask" "B.Paste")
			(net "P3V3_STBY")
			(options
				(clearance outline)
				(anchor circle)
			)
			(primitives
				(gr_poly
					(pts
						(xy 0.1524 0.381)
						(arc
							(start 0.1524 -0.2286)
							(mid 0 -0.381)
							(end -0.1524 -0.2286)
						)
						(xy -0.1524 0.381)
					)
					(width 0)
					(fill yes)
				)
			)
		)
		(pad "15" smd rect
			(at 0 0 270)
			(size 1.8288 1.8288)
			(layers "B.Cu" "B.Mask" "B.Paste")
			(net "GND")
		)
	)
)
